# S9S_MB_2U (Grand Teton) — schematic netlist excerpt (pin names and nets, part order shuffled) for the footprints in the layout excerpt that follows; sources: Cadence DE-HDL packaged netlist, KiCad conversion of 03242023_DA0F0TMBIJ0_F0T_Motherboard_J_brd_V01_OCP.brd

PC2350  Q_CAP  1NF 50V 10% EMPTY  pkg 0402  page 303 : A = HSC_OCREF ; B = AGND_HSC
C854  Q_CAP_DIFFBUS  DIFF BUS_0.22UF 6.3V 20% X6S  pkg C0201  page 174 : \1\ = P5E_CPU0_PE1_TX_C_DN<7> ; \2\ = P5E_CPU0_PE1_TX_DN<7>
PC549  Q_CAP  3300PF 50V 10% X7R  pkg 0402  page 284 : A = SH_PVCCIN_CPU1_R ; B = VSENSE_PVCCIN_CPU1_DN

(kicad_pcb
	(version 20260206)
	(generator "pcbnew")
	(generator_version "10.0")
	(general
		(thickness 1.6)
		(legacy_teardrops no)
	)
	(paper "A4")
	(title_block
		(title "03242023_DA0F0TMBIJ0_F0T_Motherboard_J_brd_V01_OCP.brd")
		(comment 1 "Grand Teton / footprints 833-835 of 6105")
	)
	(layers
		(0 "F.Cu" signal "TOP")
		(4 "In1.Cu" signal "GND")
		(6 "In2.Cu" signal "IN1")
		(8 "In3.Cu" signal "GND1")
		(10 "In4.Cu" signal "IN2")
		(12 "In5.Cu" signal "GND2")
		(14 "In6.Cu" signal "IN3")
		(16 "In7.Cu" signal "GND3")
		(18 "In8.Cu" signal "VCC")
		(20 "In9.Cu" signal "VCC1")
		(22 "In10.Cu" signal "GND4")
		(24 "In11.Cu" signal "IN4")
		(26 "In12.Cu" signal "GND5")
		(28 "In13.Cu" signal "IN5")
		(30 "In14.Cu" signal "GND6")
		(32 "In15.Cu" signal "IN6")
		(34 "In16.Cu" signal "GND7")
		(2 "B.Cu" signal "BOTTOM")
		(9 "F.Adhes" user "F.Adhesive")
		(11 "B.Adhes" user "B.Adhesive")
		(13 "F.Paste" user "Package Geometry/Pastemask Top")
		(15 "B.Paste" user "Package Geometry/Pastemask Bottom")
		(5 "F.SilkS" user "Ref Des/Silkscreen Top")
		(7 "B.SilkS" user "Ref Des/Silkscreen Bottom")
		(1 "F.Mask" user "Board Geometry/Soldermask Top")
		(3 "B.Mask" user "Board Geometry/Soldermask Bottom")
		(17 "Dwgs.User" user "User.Drawings")
		(19 "Cmts.User" user "User.Comments")
		(21 "Eco1.User" user "User.Eco1")
		(23 "Eco2.User" user "User.Eco2")
		(25 "Edge.Cuts" user "Board Geometry/Outline")
		(27 "Margin" user)
		(31 "F.CrtYd" user "Package Geometry/Place Bound Top")
		(29 "B.CrtYd" user "Package Geometry/Place Bound Bottom")
		(35 "F.Fab" user "Ref Des/Assembly Top")
		(33 "B.Fab" user "Ref Des/Assembly Bottom")
	)
	(footprint ""
		(layer "F.Cu")
		(at 105.912158 -353.137724)
		(property "Reference" "PC549"
			(at 0 0 0)
			(layer "F.SilkS")
			(hide yes)
			(effects
				(font
					(size 1.27 1.27)
				)
			)
		)
		(property "Value" ""
			(at 0 0 0)
			(layer "F.Fab")
			(effects
				(font
					(size 1.27 1.27)
				)
			)
		)
		(duplicate_pad_numbers_are_jumpers no)
		(fp_line
			(start -0.7874 -0.4064)
			(end 0.7874 -0.4064)
			(stroke
				(width 0.1524)
				(type default)
			)
			(layer "F.SilkS")
		)
		(fp_line
			(start -0.7874 0.4064)
			(end -0.7874 -0.4064)
			(stroke
				(width 0.1524)
				(type default)
			)
			(layer "F.SilkS")
		)
		(fp_line
			(start 0.7874 -0.4064)
			(end 0.7874 0.4064)
			(stroke
				(width 0.1524)
				(type default)
			)
			(layer "F.SilkS")
		)
		(fp_line
			(start 0.7874 0.4064)
			(end -0.7874 0.4064)
			(stroke
				(width 0.1524)
				(type default)
			)
			(layer "F.SilkS")
		)
		(fp_line
			(start -0.67945 -0.305054)
			(end -0.12065 -0.305054)
			(stroke
				(width 0.1)
				(type default)
			)
			(layer "F.Fab")
		)
		(fp_line
			(start -0.67945 0.3048)
			(end -0.67945 -0.305054)
			(stroke
				(width 0.1)
				(type default)
			)
			(layer "F.Fab")
		)
		(fp_line
			(start -0.12065 -0.305054)
			(end -0.12065 -0.2794)
			(stroke
				(width 0.1)
				(type default)
			)
			(layer "F.Fab")
		)
		(fp_line
			(start -0.12065 -0.2794)
			(end 0.12065 -0.2794)
			(stroke
				(width 0.1)
				(type default)
			)
			(layer "F.Fab")
		)
		(fp_line
			(start -0.12065 0.2794)
			(end -0.12065 0.3048)
			(stroke
				(width 0.1)
				(type default)
			)
			(layer "F.Fab")
		)
		(fp_line
			(start -0.12065 0.3048)
			(end -0.67945 0.3048)
			(stroke
				(width 0.1)
				(type default)
			)
			(layer "F.Fab")
		)
		(fp_line
			(start 0.120396 0.2794)
			(end -0.12065 0.2794)
			(stroke
				(width 0.1)
				(type default)
			)
			(layer "F.Fab")
		)
		(fp_line
			(start 0.120396 0.3048)
			(end 0.120396 0.2794)
			(stroke
				(width 0.1)
				(type default)
			)
			(layer "F.Fab")
		)
		(fp_line
			(start 0.12065 -0.3048)
			(end 0.67945 -0.3048)
			(stroke
				(width 0.1)
				(type default)
			)
			(layer "F.Fab")
		)
		(fp_line
			(start 0.12065 -0.2794)
			(end 0.12065 -0.3048)
			(stroke
				(width 0.1)
				(type default)
			)
			(layer "F.Fab")
		)
		(fp_line
			(start 0.67945 -0.3048)
			(end 0.67945 0.3048)
			(stroke
				(width 0.1)
				(type default)
			)
			(layer "F.Fab")
		)
		(fp_line
			(start 0.67945 0.3048)
			(end 0.120396 0.3048)
			(stroke
				(width 0.1)
				(type default)
			)
			(layer "F.Fab")
		)
		(pad "1" smd circle
			(at -0.40005 0)
			(size 0 0)
			(layers "F.Cu" "F.Mask" "F.Paste")
			(net "SH_PVCCIN_CPU1_R")
		)
		(pad "2" smd circle
			(at 0.40005 0)
			(size 0 0)
			(layers "F.Cu" "F.Mask" "F.Paste")
			(net "VSENSE_PVCCIN_CPU1_DN")
		)
	)
	(footprint ""
		(layer "F.Cu")
		(at 216.065608 -399.743422 180)
		(property "Reference" "PC2350"
			(at 0 0 180)
			(layer "F.SilkS")
			(hide yes)
			(effects
				(font
					(size 1.27 1.27)
				)
			)
		)
		(property "Value" ""
			(at 0 0 180)
			(layer "F.Fab")
			(effects
				(font
					(size 1.27 1.27)
				)
			)
		)
		(duplicate_pad_numbers_are_jumpers no)
		(fp_line
			(start 0.7874 0.4064)
			(end -0.7874 0.4064)
			(stroke
				(width 0.1524)
				(type default)
			)
			(layer "F.SilkS")
		)
		(fp_line
			(start 0.7874 -0.4064)
			(end 0.7874 0.4064)
			(stroke
				(width 0.1524)
				(type default)
			)
			(layer "F.SilkS")
		)
		(fp_line
			(start -0.7874 0.4064)
			(end -0.7874 -0.4064)
			(stroke
				(width 0.1524)
				(type default)
			)
			(layer "F.SilkS")
		)
		(fp_line
			(start -0.7874 -0.4064)
			(end 0.7874 -0.4064)
			(stroke
				(width 0.1524)
				(type default)
			)
			(layer "F.SilkS")
		)
		(fp_line
			(start 0.67945 0.3048)
			(end 0.120396 0.3048)
			(stroke
				(width 0.1)
				(type default)
			)
			(layer "F.Fab")
		)
		(fp_line
			(start 0.67945 -0.3048)
			(end 0.67945 0.3048)
			(stroke
				(width 0.1)
				(type default)
			)
			(layer "F.Fab")
		)
		(fp_line
			(start 0.12065 -0.2794)
			(end 0.12065 -0.3048)
			(stroke
				(width 0.1)
				(type default)
			)
			(layer "F.Fab")
		)
		(fp_line
			(start 0.12065 -0.3048)
			(end 0.67945 -0.3048)
			(stroke
				(width 0.1)
				(type default)
			)
			(layer "F.Fab")
		)
		(fp_line
			(start 0.120396 0.3048)
			(end 0.120396 0.2794)
			(stroke
				(width 0.1)
				(type default)
			)
			(layer "F.Fab")
		)
		(fp_line
			(start 0.120396 0.2794)
			(end -0.12065 0.2794)
			(stroke
				(width 0.1)
				(type default)
			)
			(layer "F.Fab")
		)
		(fp_line
			(start -0.12065 0.3048)
			(end -0.67945 0.3048)
			(stroke
				(width 0.1)
				(type default)
			)
			(layer "F.Fab")
		)
		(fp_line
			(start -0.12065 0.2794)
			(end -0.12065 0.3048)
			(stroke
				(width 0.1)
				(type default)
			)
			(layer "F.Fab")
		)
		(fp_line
			(start -0.12065 -0.2794)
			(end 0.12065 -0.2794)
			(stroke
				(width 0.1)
				(type default)
			)
			(layer "F.Fab")
		)
		(fp_line
			(start -0.12065 -0.305054)
			(end -0.12065 -0.2794)
			(stroke
				(width 0.1)
				(type default)
			)
			(layer "F.Fab")
		)
		(fp_line
			(start -0.67945 0.3048)
			(end -0.67945 -0.305054)
			(stroke
				(width 0.1)
				(type default)
			)
			(layer "F.Fab")
		)
		(fp_line
			(start -0.67945 -0.305054)
			(end -0.12065 -0.305054)
			(stroke
				(width 0.1)
				(type default)
			)
			(layer "F.Fab")
		)
		(pad "1" smd circle
			(at -0.40005 0 180)
			(size 0 0)
			(layers "F.Cu" "F.Mask" "F.Paste")
			(net "HSC_OCREF")
		)
		(pad "2" smd circle
			(at 0.40005 0 180)
			(size 0 0)
			(layers "F.Cu" "F.Mask" "F.Paste")
			(net "AGND_HSC")
		)
	)
	(footprint ""
		(layer "F.Cu")
		(at 413.282384 -16.088614 90)
		(property "Reference" "C854"
			(at 0 0 90)
			(layer "F.SilkS")
			(hide yes)
			(effects
				(font
					(size 1.27 1.27)
				)
			)
		)
		(property "Value" ""
			(at 0 0 90)
			(layer "F.Fab")
			(effects
				(font
					(size 1.27 1.27)
				)
			)
		)
		(duplicate_pad_numbers_are_jumpers no)
		(fp_line
			(start 0.299974 -0.150114)
			(end 0.299974 0.150114)
			(stroke
				(width 0.1)
				(type default)
			)
			(layer "F.Fab")
		)
		(fp_line
			(start -0.299974 -0.150114)
			(end 0.299974 -0.150114)
			(stroke
				(width 0.1)
				(type default)
			)
			(layer "F.Fab")
		)
		(fp_line
			(start 0.299974 0.150114)
			(end -0.299974 0.150114)
			(stroke
				(width 0.1)
				(type default)
			)
			(layer "F.Fab")
		)
		(fp_line
			(start -0.299974 0.150114)
			(end -0.299974 -0.150114)
			(stroke
				(width 0.1)
				(type default)
			)
			(layer "F.Fab")
		)
		(pad "1" smd rect
			(at -0.2667 0 90)
			(size 0.3048 0.381)
			(layers "F.Cu" "F.Mask" "F.Paste")
			(net "P5E_CPU0_PE1_TX_C_DN<7>")
		)
		(pad "2" smd rect
			(at 0.2667 0 90)
			(size 0.3048 0.381)
			(layers "F.Cu" "F.Mask" "F.Paste")
			(net "P5E_CPU0_PE1_TX_DN<7>")
		)
	)
)
